# S9S_MB_2U (Grand Teton) — schematic netlist excerpt (pin names and nets, part order shuffled) for the footprints in the layout excerpt that follows; sources: Cadence DE-HDL packaged netlist, KiCad conversion of 03242023_DA0F0TMBIJ0_F0T_Motherboard_J_brd_V01_OCP.brd

PR3981  Q_RES  0 5% CHIP  pkg 0402LF  page 303 : A = HSC_VDD_R_4 ; B = HSC_VDD
R336  Q_RES  0 5% CHIP  pkg 0402LF  page 225 : A = H_CPU0_ERR0_LVC1_R_N ; B = H_CPU_ERR0_LVC1_R_N

(kicad_pcb
	(version 20260206)
	(generator "pcbnew")
	(generator_version "10.0")
	(general
		(thickness 1.6)
		(legacy_teardrops no)
	)
	(paper "A4")
	(title_block
		(title "03242023_DA0F0TMBIJ0_F0T_Motherboard_J_brd_V01_OCP.brd")
		(comment 1 "Grand Teton / footprints 5811-5812 of 6105")
	)
	(layers
		(0 "F.Cu" signal "TOP")
		(4 "In1.Cu" signal "GND")
		(6 "In2.Cu" signal "IN1")
		(8 "In3.Cu" signal "GND1")
		(10 "In4.Cu" signal "IN2")
		(12 "In5.Cu" signal "GND2")
		(14 "In6.Cu" signal "IN3")
		(16 "In7.Cu" signal "GND3")
		(18 "In8.Cu" signal "VCC")
		(20 "In9.Cu" signal "VCC1")
		(22 "In10.Cu" signal "GND4")
		(24 "In11.Cu" signal "IN4")
		(26 "In12.Cu" signal "GND5")
		(28 "In13.Cu" signal "IN5")
		(30 "In14.Cu" signal "GND6")
		(32 "In15.Cu" signal "IN6")
		(34 "In16.Cu" signal "GND7")
		(2 "B.Cu" signal "BOTTOM")
		(9 "F.Adhes" user "F.Adhesive")
		(11 "B.Adhes" user "B.Adhesive")
		(13 "F.Paste" user "Package Geometry/Pastemask Top")
		(15 "B.Paste" user "Package Geometry/Pastemask Bottom")
		(5 "F.SilkS" user "Ref Des/Silkscreen Top")
		(7 "B.SilkS" user "Ref Des/Silkscreen Bottom")
		(1 "F.Mask" user "Board Geometry/Soldermask Top")
		(3 "B.Mask" user "Board Geometry/Soldermask Bottom")
		(17 "Dwgs.User" user "User.Drawings")
		(19 "Cmts.User" user "User.Comments")
		(21 "Eco1.User" user "User.Eco1")
		(23 "Eco2.User" user "User.Eco2")
		(25 "Edge.Cuts" user "Board Geometry/Outline")
		(27 "Margin" user)
		(31 "F.CrtYd" user "Package Geometry/Place Bound Top")
		(29 "B.CrtYd" user "Package Geometry/Place Bound Bottom")
		(35 "F.Fab" user "Ref Des/Assembly Top")
		(33 "B.Fab" user "Ref Des/Assembly Bottom")
	)
	(footprint ""
		(layer "B.Cu")
		(at 226.652328 -403.769322 -90)
		(property "Reference" "PR3981"
			(at 0 0 90)
			(layer "B.SilkS")
			(hide yes)
			(effects
				(font
					(size 1.27 1.27)
				)
				(justify mirror)
			)
		)
		(property "Value" ""
			(at 0 0 90)
			(layer "B.Fab")
			(effects
				(font
					(size 1.27 1.27)
				)
				(justify mirror)
			)
		)
		(duplicate_pad_numbers_are_jumpers no)
		(fp_line
			(start -0.7874 0.4064)
			(end 0.7874 0.4064)
			(stroke
				(width 0.1524)
				(type default)
			)
			(layer "B.SilkS")
		)
		(fp_line
			(start 0.7874 0.4064)
			(end 0.7874 -0.4064)
			(stroke
				(width 0.1524)
				(type default)
			)
			(layer "B.SilkS")
		)
		(fp_line
			(start -0.7874 -0.4064)
			(end -0.7874 0.4064)
			(stroke
				(width 0.1524)
				(type default)
			)
			(layer "B.SilkS")
		)
		(fp_line
			(start 0.7874 -0.4064)
			(end -0.7874 -0.4064)
			(stroke
				(width 0.1524)
				(type default)
			)
			(layer "B.SilkS")
		)
		(fp_line
			(start -0.67945 0.3048)
			(end -0.120396 0.3048)
			(stroke
				(width 0.1)
				(type default)
			)
			(layer "B.Fab")
		)
		(fp_line
			(start -0.120396 0.3048)
			(end -0.120396 0.2794)
			(stroke
				(width 0.1)
				(type default)
			)
			(layer "B.Fab")
		)
		(fp_line
			(start 0.12065 0.3048)
			(end 0.67945 0.3048)
			(stroke
				(width 0.1)
				(type default)
			)
			(layer "B.Fab")
		)
		(fp_line
			(start 0.67945 0.3048)
			(end 0.67945 -0.305054)
			(stroke
				(width 0.1)
				(type default)
			)
			(layer "B.Fab")
		)
		(fp_line
			(start -0.120396 0.2794)
			(end 0.12065 0.2794)
			(stroke
				(width 0.1)
				(type default)
			)
			(layer "B.Fab")
		)
		(fp_line
			(start 0.12065 0.2794)
			(end 0.12065 0.3048)
			(stroke
				(width 0.1)
				(type default)
			)
			(layer "B.Fab")
		)
		(fp_line
			(start -0.12065 -0.2794)
			(end -0.12065 -0.3048)
			(stroke
				(width 0.1)
				(type default)
			)
			(layer "B.Fab")
		)
		(fp_line
			(start 0.12065 -0.2794)
			(end -0.12065 -0.2794)
			(stroke
				(width 0.1)
				(type default)
			)
			(layer "B.Fab")
		)
		(fp_line
			(start -0.67945 -0.3048)
			(end -0.67945 0.3048)
			(stroke
				(width 0.1)
				(type default)
			)
			(layer "B.Fab")
		)
		(fp_line
			(start -0.12065 -0.3048)
			(end -0.67945 -0.3048)
			(stroke
				(width 0.1)
				(type default)
			)
			(layer "B.Fab")
		)
		(fp_line
			(start 0.12065 -0.305054)
			(end 0.12065 -0.2794)
			(stroke
				(width 0.1)
				(type default)
			)
			(layer "B.Fab")
		)
		(fp_line
			(start 0.67945 -0.305054)
			(end 0.12065 -0.305054)
			(stroke
				(width 0.1)
				(type default)
			)
			(layer "B.Fab")
		)
		(pad "1" smd circle
			(at 0.40005 0 90)
			(size 0 0)
			(layers "B.Cu" "B.Mask" "B.Paste")
			(net "HSC_VDD_R_4")
		)
		(pad "2" smd circle
			(at -0.40005 0 90)
			(size 0 0)
			(layers "B.Cu" "B.Mask" "B.Paste")
			(net "HSC_VDD")
		)
	)
	(footprint ""
		(layer "B.Cu")
		(at 321.001898 -186.43981 90)
		(property "Reference" "R336"
			(at 0 0 90)
			(layer "B.SilkS")
			(hide yes)
			(effects
				(font
					(size 1.27 1.27)
				)
				(justify mirror)
			)
		)
		(property "Value" ""
			(at 0 0 90)
			(layer "B.Fab")
			(effects
				(font
					(size 1.27 1.27)
				)
				(justify mirror)
			)
		)
		(duplicate_pad_numbers_are_jumpers no)
		(fp_line
			(start 0.7874 -0.4064)
			(end -0.7874 -0.4064)
			(stroke
				(width 0.1524)
				(type default)
			)
			(layer "B.SilkS")
		)
		(fp_line
			(start -0.7874 -0.4064)
			(end -0.7874 0.4064)
			(stroke
				(width 0.1524)
				(type default)
			)
			(layer "B.SilkS")
		)
		(fp_line
			(start 0.7874 0.4064)
			(end 0.7874 -0.4064)
			(stroke
				(width 0.1524)
				(type default)
			)
			(layer "B.SilkS")
		)
		(fp_line
			(start -0.7874 0.4064)
			(end 0.7874 0.4064)
			(stroke
				(width 0.1524)
				(type default)
			)
			(layer "B.SilkS")
		)
		(fp_line
			(start 0.67945 -0.305054)
			(end 0.12065 -0.305054)
			(stroke
				(width 0.1)
				(type default)
			)
			(layer "B.Fab")
		)
		(fp_line
			(start 0.12065 -0.305054)
			(end 0.12065 -0.2794)
			(stroke
				(width 0.1)
				(type default)
			)
			(layer "B.Fab")
		)
		(fp_line
			(start -0.12065 -0.3048)
			(end -0.67945 -0.3048)
			(stroke
				(width 0.1)
				(type default)
			)
			(layer "B.Fab")
		)
		(fp_line
			(start -0.67945 -0.3048)
			(end -0.67945 0.3048)
			(stroke
				(width 0.1)
				(type default)
			)
			(layer "B.Fab")
		)
		(fp_line
			(start 0.12065 -0.2794)
			(end -0.12065 -0.2794)
			(stroke
				(width 0.1)
				(type default)
			)
			(layer "B.Fab")
		)
		(fp_line
			(start -0.12065 -0.2794)
			(end -0.12065 -0.3048)
			(stroke
				(width 0.1)
				(type default)
			)
			(layer "B.Fab")
		)
		(fp_line
			(start 0.12065 0.2794)
			(end 0.12065 0.3048)
			(stroke
				(width 0.1)
				(type default)
			)
			(layer "B.Fab")
		)
		(fp_line
			(start -0.120396 0.2794)
			(end 0.12065 0.2794)
			(stroke
				(width 0.1)
				(type default)
			)
			(layer "B.Fab")
		)
		(fp_line
			(start 0.67945 0.3048)
			(end 0.67945 -0.305054)
			(stroke
				(width 0.1)
				(type default)
			)
			(layer "B.Fab")
		)
		(fp_line
			(start 0.12065 0.3048)
			(end 0.67945 0.3048)
			(stroke
				(width 0.1)
				(type default)
			)
			(layer "B.Fab")
		)
		(fp_line
			(start -0.120396 0.3048)
			(end -0.120396 0.2794)
			(stroke
				(width 0.1)
				(type default)
			)
			(layer "B.Fab")
		)
		(fp_line
			(start -0.67945 0.3048)
			(end -0.120396 0.3048)
			(stroke
				(width 0.1)
				(type default)
			)
			(layer "B.Fab")
		)
		(pad "1" smd circle
			(at 0.40005 0 270)
			(size 0 0)
			(layers "B.Cu" "B.Mask" "B.Paste")
			(net "H_CPU0_ERR0_LVC1_R_N")
		)
		(pad "2" smd circle
			(at -0.40005 0 270)
			(size 0 0)
			(layers "B.Cu" "B.Mask" "B.Paste")
			(net "H_CPU_ERR0_LVC1_R_N")
		)
	)
)
